(kicad_pcb
	(version 20241229)
	(generator "pcbnew")
	(generator_version "9.0")
	(general
		(thickness 1.711)
		(legacy_teardrops no)
	)
	(paper "A4")
	(title_block
		(title "Antmicro Baseboard for Jetson AGX Thor")
		(date "2026-02-18")
		(rev "1.1.0")
		(company "Antmicro Ltd")
		(comment 1 "www.antmicro.com")
		(comment 9 "footprints 720-724 of 1170")
	)
	(layers
		(0 "F.Cu" signal)
		(4 "In1.Cu" signal)
		(6 "In2.Cu" signal)
		(8 "In3.Cu" signal)
		(10 "In4.Cu" jumper)
		(12 "In5.Cu" signal)
		(14 "In6.Cu" signal)
		(16 "In7.Cu" signal)
		(18 "In8.Cu" signal)
		(2 "B.Cu" signal)
		(9 "F.Adhes" user "F.Adhesive")
		(11 "B.Adhes" user "B.Adhesive")
		(13 "F.Paste" user)
		(15 "B.Paste" user)
		(5 "F.SilkS" user "F.Silkscreen")
		(7 "B.SilkS" user "B.Silkscreen")
		(1 "F.Mask" user)
		(3 "B.Mask" user)
		(17 "Dwgs.User" user "User.Drawings")
		(19 "Cmts.User" user "User.Comments")
		(21 "Eco1.User" user "User.Eco1")
		(23 "Eco2.User" user "User.Eco2")
		(25 "Edge.Cuts" user)
		(27 "Margin" user)
		(31 "F.CrtYd" user "F.Courtyard")
		(29 "B.CrtYd" user "B.Courtyard")
		(35 "F.Fab" user)
		(33 "B.Fab" user)
	)
	(footprint "antmicro-footprints:R_0402_1005Metric"
		(layer "B.Cu")
		(at 168 63.4 -90)
		(descr "Resistor SMD 0402")
		(tags "resistor SMD 0402")
		(property "Reference" "R341"
			(at 0.9 -0.4 90)
			(layer "B.SilkS")
			(effects
				(font
					(size 0.7 0.7)
					(thickness 0.15)
				)
				(justify left bottom mirror)
			)
		)
		(property "Value" "R_0R_0402"
			(at -1.011843 -1.772046 90)
			(layer "B.Fab")
			(effects
				(font
					(size 0.7 0.7)
					(thickness 0.15)
				)
				(justify left bottom mirror)
			)
		)
		(property "Datasheet" "https://industrial.panasonic.com/cdbs/www-data/pdf/RDA0000/AOA0000C301.pdf"
			(at 0 0 90)
			(layer "B.Fab")
			(hide yes)
			(effects
				(font
					(size 1.27 1.27)
					(thickness 0.15)
				)
				(justify mirror)
			)
		)
		(property "Description" "SMD Chip Resistor, Jumper, 0 ohm, 100 mW, 0402 [1005 Metric], Thick Film, General Purpose"
			(at 0 0 90)
			(layer "B.Fab")
			(hide yes)
			(effects
				(font
					(size 1.27 1.27)
					(thickness 0.15)
				)
				(justify mirror)
			)
		)
		(property "MPN" "ERJ2GE0R00X"
			(at 0 0 90)
			(unlocked yes)
			(layer "B.Fab")
			(hide yes)
			(effects
				(font
					(size 1 1)
					(thickness 0.15)
				)
				(justify mirror)
			)
		)
		(property "Manufacturer" "Panasonic"
			(at 0 0 90)
			(unlocked yes)
			(layer "B.Fab")
			(hide yes)
			(effects
				(font
					(size 1 1)
					(thickness 0.15)
				)
				(justify mirror)
			)
		)
		(property "License" "Apache-2.0"
			(at 0 0 90)
			(unlocked yes)
			(layer "B.Fab")
			(hide yes)
			(effects
				(font
					(size 1 1)
					(thickness 0.15)
				)
				(justify mirror)
			)
		)
		(property "Author" "Antmicro"
			(at 0 0 90)
			(unlocked yes)
			(layer "B.Fab")
			(hide yes)
			(effects
				(font
					(size 1 1)
					(thickness 0.15)
				)
				(justify mirror)
			)
		)
		(property "Val" "0R"
			(at 0 0 90)
			(unlocked yes)
			(layer "B.Fab")
			(hide yes)
			(effects
				(font
					(size 1 1)
					(thickness 0.15)
				)
				(justify mirror)
			)
		)
		(property "Tolerance" "~"
			(at 0 0 90)
			(unlocked yes)
			(layer "B.Fab")
			(hide yes)
			(effects
				(font
					(size 1 1)
					(thickness 0.15)
				)
				(justify mirror)
			)
		)
		(property "Current" "1A"
			(at 0 0 90)
			(unlocked yes)
			(layer "B.Fab")
			(hide yes)
			(effects
				(font
					(size 1 1)
					(thickness 0.15)
				)
				(justify mirror)
			)
		)
		(sheetname "/SoM_IO2/")
		(sheetfile "som_io2.kicad_sch")
		(attr smd exclude_from_pos_files exclude_from_bom dnp)
		(fp_poly
			(pts
				(xy -0.925 0.47) (xy -0.925 -0.47) (xy 0.925 -0.47) (xy 0.925 0.47)
			)
			(stroke
				(width 0.05)
				(type default)
			)
			(fill no)
			(layer "B.CrtYd")
		)
		(fp_poly
			(pts
				(xy -0.5 0.25) (xy -0.5 -0.25) (xy 0.5 -0.25) (xy 0.5 0.25)
			)
			(stroke
				(width 0.15)
				(type solid)
			)
			(fill no)
			(layer "B.Fab")
		)
		(fp_text user "${REFERENCE}"
			(at -0.95 -3.168 90)
			(layer "B.Fab")
			(effects
				(font
					(size 0.7 0.7)
					(thickness 0.15)
				)
				(justify left bottom mirror)
			)
		)
		(fp_text user "License: Apache-2.0"
			(at -0.949999 -5.169 90)
			(layer "B.Fab")
			(effects
				(font
					(size 0.7 0.7)
					(thickness 0.15)
				)
				(justify left bottom mirror)
			)
		)
		(fp_text user "Author: Antmicro"
			(at -0.95 -4.169 90)
			(layer "B.Fab")
			(effects
				(font
					(size 0.7 0.7)
					(thickness 0.15)
				)
				(justify left bottom mirror)
			)
		)
		(pad "1" smd roundrect
			(at -0.48 0 270)
			(size 0.59 0.64)
			(layers "B.Cu" "B.Mask" "B.Paste")
			(roundrect_rratio 0.25)
			(net 269 "/SoM_IO2/TC_VCC")
			(pintype "passive")
		)
		(pad "2" smd roundrect
			(at 0.48 0 270)
			(size 0.59 0.64)
			(layers "B.Cu" "B.Mask" "B.Paste")
			(roundrect_rratio 0.25)
			(net 2 "+3V3")
			(pintype "passive")
		)
	)
	(footprint "antmicro-footprints:R_0402_1005Metric"
		(layer "B.Cu")
		(at 215.5 84.3 90)
		(descr "Resistor SMD 0402")
		(tags "resistor SMD 0402")
		(property "Reference" "R137"
			(at -0.97 1.6 90)
			(layer "B.SilkS")
			(effects
				(font
					(size 0.7 0.7)
					(thickness 0.15)
				)
				(justify right top mirror)
			)
		)
		(property "Value" "R_1k_0402"
			(at -1.011843 -1.772047 90)
			(layer "B.Fab")
			(effects
				(font
					(size 0.7 0.7)
					(thickness 0.15)
				)
				(justify right top mirror)
			)
		)
		(property "Datasheet" "https://www.bourns.com/docs/product-datasheets/cr.pdf"
			(at 0 0 90)
			(layer "B.Fab")
			(hide yes)
			(effects
				(font
					(size 1.27 1.27)
					(thickness 0.15)
				)
				(justify mirror)
			)
		)
		(property "Description" "SMD Chip Resistor, 1 kohm, ± 1%, 63 mW, 0402 [1005 Metric], Thick Film, General Purpose"
			(at 0 0 90)
			(layer "B.Fab")
			(hide yes)
			(effects
				(font
					(size 1.27 1.27)
					(thickness 0.15)
				)
				(justify mirror)
			)
		)
		(property "Manufacturer" "Bourns"
			(at 0 0 270)
			(unlocked yes)
			(layer "B.Fab")
			(hide yes)
			(effects
				(font
					(size 1 1)
					(thickness 0.15)
				)
				(justify mirror)
			)
		)
		(property "MPN" "CR0402-FX-1001GLF"
			(at 0 0 270)
			(unlocked yes)
			(layer "B.Fab")
			(hide yes)
			(effects
				(font
					(size 1 1)
					(thickness 0.15)
				)
				(justify mirror)
			)
		)
		(property "Val" "1k"
			(at 0 0 270)
			(unlocked yes)
			(layer "B.Fab")
			(hide yes)
			(effects
				(font
					(size 1 1)
					(thickness 0.15)
				)
				(justify mirror)
			)
		)
		(property "License" "Apache-2.0"
			(at 0 0 270)
			(unlocked yes)
			(layer "B.Fab")
			(hide yes)
			(effects
				(font
					(size 1 1)
					(thickness 0.15)
				)
				(justify mirror)
			)
		)
		(property "Author" "Antmicro"
			(at 0 0 270)
			(unlocked yes)
			(layer "B.Fab")
			(hide yes)
			(effects
				(font
					(size 1 1)
					(thickness 0.15)
				)
				(justify mirror)
			)
		)
		(property "Tolerance" "1%"
			(at 0 0 270)
			(unlocked yes)
			(layer "B.Fab")
			(hide yes)
			(effects
				(font
					(size 1 1)
					(thickness 0.15)
				)
				(justify mirror)
			)
		)
		(sheetname "/USB DP Alt mode/")
		(sheetfile "usb_dp.kicad_sch")
		(attr smd)
		(fp_rect
			(start -0.925 0.47)
			(end 0.925 -0.47)
			(stroke
				(width 0.05)
				(type default)
			)
			(fill no)
			(layer "B.CrtYd")
		)
		(fp_rect
			(start -0.5 0.25)
			(end 0.5 -0.25)
			(stroke
				(width 0.15)
				(type solid)
			)
			(fill no)
			(layer "B.Fab")
		)
		(fp_text user "Author: Antmicro"
			(at -0.95 -4.169 90)
			(layer "B.Fab")
			(effects
				(font
					(size 0.7 0.7)
					(thickness 0.15)
				)
				(justify right top mirror)
			)
		)
		(fp_text user "${REFERENCE}"
			(at -0.95 -3.168 90)
			(layer "B.Fab")
			(effects
				(font
					(size 0.7 0.7)
					(thickness 0.15)
				)
				(justify right top mirror)
			)
		)
		(fp_text user "License: Apache-2.0"
			(at -0.95 -5.169 90)
			(layer "B.Fab")
			(effects
				(font
					(size 0.7 0.7)
					(thickness 0.15)
				)
				(justify right top mirror)
			)
		)
		(pad "1" smd roundrect
			(at -0.48 0 90)
			(size 0.59 0.64)
			(layers "B.Cu" "B.Mask" "B.Paste")
			(roundrect_rratio 0.25)
			(net 967 "/USB DP Alt mode/USBC1_DPEQ1")
			(pintype "passive")
		)
		(pad "2" smd roundrect
			(at 0.48 0 90)
			(size 0.59 0.64)
			(layers "B.Cu" "B.Mask" "B.Paste")
			(roundrect_rratio 0.25)
			(net 1 "GND")
			(pintype "passive")
		)
	)
	(footprint "antmicro-footprints:TP_SMD_0.75mm"
		(layer "B.Cu")
		(at 83.5 59.9 -90)
		(property "Reference" "TP84"
			(at 0.44 0.51 180)
			(layer "B.SilkS")
			(effects
				(font
					(size 0.7 0.7)
					(thickness 0.15)
				)
				(justify left bottom mirror)
			)
		)
		(property "Value" "TP_0.75mm_SMD"
			(at 0 -1.2 90)
			(layer "B.Fab")
			(effects
				(font
					(size 0.7 0.7)
					(thickness 0.15)
				)
				(justify left bottom mirror)
			)
		)
		(property "Description" "SMT test point"
			(at 0 0 90)
			(layer "B.Fab")
			(hide yes)
			(effects
				(font
					(size 1.27 1.27)
					(thickness 0.15)
				)
				(justify mirror)
			)
		)
		(property "MPN" ""
			(at 0 0 90)
			(unlocked yes)
			(layer "B.Fab")
			(hide yes)
			(effects
				(font
					(size 1 1)
					(thickness 0.15)
				)
				(justify mirror)
			)
		)
		(property "Manufacturer" ""
			(at 0 0 90)
			(unlocked yes)
			(layer "B.Fab")
			(hide yes)
			(effects
				(font
					(size 1 1)
					(thickness 0.15)
				)
				(justify mirror)
			)
		)
		(property "Author" "Antmicro"
			(at 0 0 90)
			(unlocked yes)
			(layer "B.Fab")
			(hide yes)
			(effects
				(font
					(size 1 1)
					(thickness 0.15)
				)
				(justify mirror)
			)
		)
		(property "License" "Apache-2.0"
			(at 0 0 90)
			(unlocked yes)
			(layer "B.Fab")
			(hide yes)
			(effects
				(font
					(size 1 1)
					(thickness 0.15)
				)
				(justify mirror)
			)
		)
		(sheetname "/SoM_Power/")
		(sheetfile "som_power.kicad_sch")
		(attr exclude_from_pos_files exclude_from_bom)
		(fp_circle
			(center 0 0)
			(end 0.475 0)
			(stroke
				(width 0.05)
				(type default)
			)
			(fill no)
			(layer "B.CrtYd")
		)
		(fp_text user "Author: Antmicro"
			(at -0.4 -3.901 90)
			(layer "B.Fab")
			(effects
				(font
					(size 0.7 0.7)
					(thickness 0.15)
				)
				(justify left bottom mirror)
			)
		)
		(fp_text user "${REFERENCE}"
			(at -0.4 -2.7 90)
			(layer "B.Fab")
			(effects
				(font
					(size 0.7 0.7)
					(thickness 0.15)
				)
				(justify left bottom mirror)
			)
		)
		(fp_text user "License: Apache-2.0"
			(at -0.4 -5.101 90)
			(layer "B.Fab")
			(effects
				(font
					(size 0.7 0.7)
					(thickness 0.15)
				)
				(justify left bottom mirror)
			)
		)
		(pad "1" smd circle
			(at 0 0 270)
			(size 0.75 0.75)
			(layers "B.Cu" "B.Mask")
			(net 683 "/SoM_Power/~{SOM_PRSNT}")
			(pinfunction "1")
			(pintype "passive")
		)
	)
	(footprint "antmicro-footprints:TP_SMD_0.75mm"
		(layer "B.Cu")
		(at 102.4 76.7 180)
		(property "Reference" "TP74"
			(at 0 0.6 0)
			(layer "B.SilkS")
			(effects
				(font
					(size 0.7 0.7)
					(thickness 0.15)
				)
				(justify left bottom mirror)
			)
		)
		(property "Value" "TP_0.75mm_SMD"
			(at 0 -1.2 0)
			(layer "B.Fab")
			(effects
				(font
					(size 0.7 0.7)
					(thickness 0.15)
				)
				(justify left bottom mirror)
			)
		)
		(property "Description" "SMT test point"
			(at 0 0 0)
			(layer "B.Fab")
			(hide yes)
			(effects
				(font
					(size 1.27 1.27)
					(thickness 0.15)
				)
				(justify mirror)
			)
		)
		(property "MPN" ""
			(at 0 0 0)
			(unlocked yes)
			(layer "B.Fab")
			(hide yes)
			(effects
				(font
					(size 1 1)
					(thickness 0.15)
				)
				(justify mirror)
			)
		)
		(property "Manufacturer" ""
			(at 0 0 0)
			(unlocked yes)
			(layer "B.Fab")
			(hide yes)
			(effects
				(font
					(size 1 1)
					(thickness 0.15)
				)
				(justify mirror)
			)
		)
		(property "Author" "Antmicro"
			(at 0 0 0)
			(unlocked yes)
			(layer "B.Fab")
			(hide yes)
			(effects
				(font
					(size 1 1)
					(thickness 0.15)
				)
				(justify mirror)
			)
		)
		(property "License" "Apache-2.0"
			(at 0 0 0)
			(unlocked yes)
			(layer "B.Fab")
			(hide yes)
			(effects
				(font
					(size 1 1)
					(thickness 0.15)
				)
				(justify mirror)
			)
		)
		(sheetname "/SoM_IO/")
		(sheetfile "som_io.kicad_sch")
		(attr exclude_from_pos_files exclude_from_bom)
		(fp_circle
			(center 0 0)
			(end 0.475 0)
			(stroke
				(width 0.05)
				(type default)
			)
			(fill no)
			(layer "B.CrtYd")
		)
		(fp_text user "Author: Antmicro"
			(at -0.4 -3.901 0)
			(layer "B.Fab")
			(effects
				(font
					(size 0.7 0.7)
					(thickness 0.15)
				)
				(justify left bottom mirror)
			)
		)
		(fp_text user "License: Apache-2.0"
			(at -0.4 -5.101 0)
			(layer "B.Fab")
			(effects
				(font
					(size 0.7 0.7)
					(thickness 0.15)
				)
				(justify left bottom mirror)
			)
		)
		(fp_text user "${REFERENCE}"
			(at -0.4 -2.7 0)
			(layer "B.Fab")
			(effects
				(font
					(size 0.7 0.7)
					(thickness 0.15)
				)
				(justify left bottom mirror)
			)
		)
		(pad "1" smd circle
			(at 0 0 180)
			(size 0.75 0.75)
			(layers "B.Cu" "B.Mask")
			(net 111 "/Expansion connector/I2S3.FS")
			(pinfunction "1")
			(pintype "passive")
		)
	)
	(footprint "antmicro-footprints:C_0805_2012Metric"
		(layer "B.Cu")
		(at 85.2 67.2)
		(descr "Capacitor SMD 0805")
		(tags "capacitor SMD 0805")
		(property "Reference" "C27"
			(at -1.06 1.09 0)
			(layer "B.SilkS")
			(effects
				(font
					(size 0.7 0.7)
					(thickness 0.15)
				)
				(justify right top mirror)
			)
		)
		(property "Value" "C_22u_25V_0805"
			(at -2.055717 -1.963153 0)
			(layer "B.Fab")
			(effects
				(font
					(size 0.7 0.7)
					(thickness 0.15)
				)
				(justify right top mirror)
			)
		)
		(property "Datasheet" "https://product.samsungsem.com/mlcc/CL21A226MAYNNN.do"
			(at 0 0 0)
			(layer "B.Fab")
			(hide yes)
			(effects
				(font
					(size 1.27 1.27)
					(thickness 0.15)
				)
				(justify mirror)
			)
		)
		(property "Description" "SMT Multilayer Ceramic Capacitor, 22uF, +/-20%, 25V, X5R, 0805 [2012 Metric]"
			(at 0 0 0)
			(layer "B.Fab")
			(hide yes)
			(effects
				(font
					(size 1.27 1.27)
					(thickness 0.15)
				)
				(justify mirror)
			)
		)
		(property "MPN" "CL21A226MAYNNNE"
			(at 0 0 180)
			(unlocked yes)
			(layer "B.Fab")
			(hide yes)
			(effects
				(font
					(size 1 1)
					(thickness 0.15)
				)
				(justify mirror)
			)
		)
		(property "Manufacturer" "Samsung Electro-Mechanics"
			(at 0 0 180)
			(unlocked yes)
			(layer "B.Fab")
			(hide yes)
			(effects
				(font
					(size 1 1)
					(thickness 0.15)
				)
				(justify mirror)
			)
		)
		(property "License" "Apache-2.0"
			(at 0 0 180)
			(unlocked yes)
			(layer "B.Fab")
			(hide yes)
			(effects
				(font
					(size 1 1)
					(thickness 0.15)
				)
				(justify mirror)
			)
		)
		(property "Author" "Antmicro"
			(at 0 0 180)
			(unlocked yes)
			(layer "B.Fab")
			(hide yes)
			(effects
				(font
					(size 1 1)
					(thickness 0.15)
				)
				(justify mirror)
			)
		)
		(property "Val" "22u"
			(at 0 0 180)
			(unlocked yes)
			(layer "B.Fab")
			(hide yes)
			(effects
				(font
					(size 1 1)
					(thickness 0.15)
				)
				(justify mirror)
			)
		)
		(property "Voltage" "25V"
			(at 0 0 180)
			(unlocked yes)
			(layer "B.Fab")
			(hide yes)
			(effects
				(font
					(size 1 1)
					(thickness 0.15)
				)
				(justify mirror)
			)
		)
		(property "Dielectric" "X5R"
			(at 0 0 180)
			(unlocked yes)
			(layer "B.Fab")
			(hide yes)
			(effects
				(font
					(size 1 1)
					(thickness 0.15)
				)
				(justify mirror)
			)
		)
		(property "Public" "False"
			(at 0 0 180)
			(unlocked yes)
			(layer "B.Fab")
			(hide yes)
			(effects
				(font
					(size 1 1)
					(thickness 0.15)
				)
				(justify mirror)
			)
		)
		(sheetname "/SoM_Power/")
		(sheetfile "som_power.kicad_sch")
		(attr smd)
		(fp_line
			(start -0.3 -0.7)
			(end 0.3 -0.7)
			(stroke
				(width 0.15)
				(type solid)
			)
			(layer "B.SilkS")
		)
		(fp_line
			(start -0.3 0.7)
			(end 0.3 0.7)
			(stroke
				(width 0.15)
				(type solid)
			)
			(layer "B.SilkS")
		)
		(fp_poly
			(pts
				(xy 1.95 0.9) (xy -1.95 0.9) (xy -1.95 -0.9) (xy 1.95 -0.9)
			)
			(stroke
				(width 0.05)
				(type default)
			)
			(fill no)
			(layer "B.CrtYd")
		)
		(fp_poly
			(pts
				(xy -0.95 0.675001) (xy 0.95 0.675001) (xy 0.95 -0.675001) (xy -0.95 -0.675001)
			)
			(stroke
				(width 0.15)
				(type solid)
			)
			(fill no)
			(layer "B.Fab")
		)
		(fp_text user "${REFERENCE}"
			(at -1.899999 -3.947 0)
			(layer "B.Fab")
			(effects
				(font
					(size 0.7 0.7)
					(thickness 0.15)
				)
				(justify right top mirror)
			)
		)
		(fp_text user "License: Apache-2.0"
			(at -1.9 -4.947 0)
			(layer "B.Fab")
			(effects
				(font
					(size 0.7 0.7)
					(thickness 0.15)
				)
				(justify right top mirror)
			)
		)
		(fp_text user "Author: Antmicro"
			(at -1.9 -5.947 0)
			(layer "B.Fab")
			(effects
				(font
					(size 0.7 0.7)
					(thickness 0.15)
				)
				(justify right top mirror)
			)
		)
		(pad "1" smd roundrect
			(at -1.099999 0)
			(size 1.2 1.3)
			(layers "B.Cu" "B.Mask" "B.Paste")
			(roundrect_rratio 0.25)
			(net 1 "GND")
			(pintype "passive")
		)
		(pad "2" smd roundrect
			(at 1.099999 0)
			(size 1.2 1.3)
			(layers "B.Cu" "B.Mask" "B.Paste")
			(roundrect_rratio 0.25)
			(net 12 "SYS_VIN_HV")
			(pintype "passive")
		)
	)
)
